FILE_TYPE = CONNECTIVITY;
{Allegro Design Entry HDL 17.4-2019 S026 (4007227) 1/17/2022}
"PAGE_NUMBER" = 255;
0"NC";
1"GND\g";
2"GND\g";
3"P3V3_AUX\g";
4"GND\g";
5"P3V3_AUX\g";
6"GND\g";
7"P3V3_AUX\g";
8"GND\g";
9"P3V3_AUX\g";
10"GND\g";
11"P3V3_AUX\g";
12"P3V3_AUX\g";
13"GND\g";
14"GND\g";
15"GND\g";
16"GND\g";
17"GPU_NVS_PWR_BRAKE_N";
18"GPU_FPGA_EROT_RECOV_N";
19"GPU_FPGA_EROT_RST_N";
20"GPU_FPGA_EROT_RECOV_BUF_R_N";
21"GPU_FPGA_EROT_RST_BUF_R_N";
22"NC_U257_2Y";
23"GPU_NVS_PWR_BRAKE_N_R";
24"P3V3_AUX\g";
25"GPU_FPGA_EROT_RECOV_BUF_N";
26"GPU_FPGA_EROT_RST_BUF_N";
27"GPU_NVS_PWR_BRAKE_N_BUF";
28"P3V3_AUX\g";
%"UNIVERSAL_POWER"
"1","(1350,3875)","0","pure_quanta_power","I11";
;
HDL_POWER"P3V3_AUX"
CDS_LIB"pure_quanta_power";
"A"28;
%"UNIVERSAL_GND"
"1","(1350,3325)","0","pure_quanta_power","I12";
;
CDS_LIB"pure_quanta_power"
HDL_POWER"GND";
"A"1;
%"Q_CAP"
"1","(1350,3550)","0","pure_quanta","I13";
;
LOCATION"C1963"
$SEC"1"
CDS_SEC"1"
TOLERANCE"10%"
VOLTAGE"25V"
PACK_TYPE"0402"
VALUE"0.1UF"
MATERIAL"X7R"
CDS_LIB"pure_quanta"
PART_NUMBER"CH4104K1B00";
"B"
$PN"2"1;
"A"
$PN"1"28;
%"74LVC2G07DW7"
"1","(775,3750)","0","pure_quanta","I16";
;
LOCATION"U255"
$SEC"1"
CDS_SEC"1"
VALUE"74LVC2G07DW-7"
PART_TYPE"SMLF"
MATERIAL"IC"
CDS_LIB"pure_quanta"
NEEDS_NO_SIZE"TRUE"
CDS_LMAN_SYM_OUTLINE"-175,100,175,-100"
PART_NUMBER"AL002G07003";
"VCC"
$PN"5"28;
"GND"
$PN"2"2;
"2Y"
$PN"4"21;
"1Y"
$PN"6"23;
"2A"
$PN"3"19;
"1A"
$PN"1"17;
%"UNIVERSAL_GND"
"1","(200,3600)","0","pure_quanta_power","I17";
;
CDS_LIB"pure_quanta_power"
HDL_POWER"GND";
"A"2;
%"UNIVERSAL_POWER"
"1","(-650,4825)","0","pure_quanta_power","I28";
;
HDL_POWER"P3V3_AUX"
CDS_LIB"pure_quanta_power";
"A"3;
%"UNIVERSAL_GND"
"1","(-625,3900)","0","pure_quanta_power","I30";
;
CDS_LIB"pure_quanta_power"
HDL_POWER"GND";
"A"4;
%"Q_RES"
"2","(-625,4100)","0","pure_quanta","I31";
;
LOCATION"R3460"
$SEC"1"
CDS_SEC"1"
TOLERANCE"1%"
VALUE"100K"
WATTAGE"1/16W"
PACK_TYPE"0402LF"
MATERIAL"EMPTY"
CDS_LIB"pure_quanta"
PART_NUMBER"CS41002FB09";
"A"
$PN"1"17;
"B"
$PN"2"4;
%"Q_RES"
"2","(1875,4000)","0","pure_quanta","I33";
;
LOCATION"R3462"
$SEC"1"
CDS_SEC"1"
PACK_TYPE"0402LF"
MATERIAL"EMPTY"
WATTAGE"1/16W"
TOLERANCE"1%"
VALUE"100K"
CDS_LIB"pure_quanta"
PART_NUMBER"CS41002FB09";
"A"
$PN"1"23;
"B"
$PN"2"6;
%"UNIVERSAL_POWER"
"1","(1850,4850)","0","pure_quanta_power","I34";
;
HDL_POWER"P3V3_AUX"
CDS_LIB"pure_quanta_power";
"A"5;
%"Q_RES"
"2","(1850,4600)","0","pure_quanta","I35";
;
LOCATION"R3461"
$SEC"1"
CDS_SEC"1"
WATTAGE"1/16W"
VALUE"54.9K"
TOLERANCE"1%"
MATERIAL"CHIP"
PACK_TYPE"0402LF"
CDS_LIB"pure_quanta"
PART_NUMBER"CS35492FB03";
"A"
$PN"1"5;
"B"
$PN"2"23;
%"Q_RES"
"1","(2100,4300)","0","pure_quanta","I37";
;
LOCATION"R3397"
$SEC"1"
CDS_SEC"1"
VALUE"33.2"
PACK_TYPE"0402LF"
MATERIAL"CHIP"
CDS_LIB"pure_quanta"
TOLERANCE"1%"
WATTAGE"1/16W"
PART_NUMBER"CS03322FB03";
"B"
$PN"2"27;
"A"
$PN"1"23;
%"UNIVERSAL_GND"
"1","(1875,3800)","0","pure_quanta_power","I38";
;
CDS_LIB"pure_quanta_power"
HDL_POWER"GND";
"A"6;
%"UNIVERSAL_POWER"
"1","(-650,3675)","0","pure_quanta_power","I39";
;
HDL_POWER"P3V3_AUX"
CDS_LIB"pure_quanta_power";
"A"7;
%"Q_RES"
"2","(-650,3425)","0","pure_quanta","I40";
;
LOCATION"R3488"
$SEC"1"
CDS_SEC"1"
WATTAGE"1/16W"
MATERIAL"CHIP"
PACK_TYPE"0402LF"
VALUE"1K"
TOLERANCE"1%"
CDS_LIB"pure_quanta"
PART_NUMBER"CS21002FB06";
"A"
$PN"1"7;
"B"
$PN"2"19;
%"Q_RES"
"2","(-625,2950)","0","pure_quanta","I42";
;
LOCATION"R3489"
$SEC"1"
CDS_SEC"1"
MATERIAL"EMPTY"
PACK_TYPE"0402LF"
WATTAGE"1/16W"
VALUE"100K"
TOLERANCE"1%"
CDS_LIB"pure_quanta"
PART_NUMBER"CS41002FB09";
"A"
$PN"1"19;
"B"
$PN"2"8;
%"UNIVERSAL_GND"
"1","(-625,2750)","0","pure_quanta_power","I43";
;
CDS_LIB"pure_quanta_power"
HDL_POWER"GND";
"A"8;
%"Q_RES"
"1","(2150,3100)","0","pure_quanta","I45";
;
LOCATION"R3496"
$SEC"1"
CDS_SEC"1"
VALUE"33.2"
PACK_TYPE"0402LF"
MATERIAL"CHIP"
CDS_LIB"pure_quanta"
TOLERANCE"1%"
WATTAGE"1/16W"
PART_NUMBER"CS03322FB03";
"B"
$PN"2"26;
"A"
$PN"1"21;
%"UNIVERSAL_POWER"
"1","(1900,3650)","0","pure_quanta_power","I46";
;
HDL_POWER"P3V3_AUX"
CDS_LIB"pure_quanta_power";
"A"9;
%"Q_RES"
"2","(1900,3400)","0","pure_quanta","I47";
;
LOCATION"R3492"
$SEC"1"
CDS_SEC"1"
WATTAGE"1/16W"
VALUE"54.9K"
TOLERANCE"1%"
MATERIAL"CHIP"
PACK_TYPE"0402LF"
CDS_LIB"pure_quanta"
PART_NUMBER"CS35492FB03";
"A"
$PN"1"9;
"B"
$PN"2"21;
%"Q_RES"
"2","(1925,2800)","0","pure_quanta","I48";
;
LOCATION"R3493"
$SEC"1"
CDS_SEC"1"
WATTAGE"1/16W"
TOLERANCE"1%"
VALUE"100K"
MATERIAL"EMPTY"
PACK_TYPE"0402LF"
CDS_LIB"pure_quanta"
PART_NUMBER"CS41002FB09";
"A"
$PN"1"21;
"B"
$PN"2"10;
%"UNIVERSAL_GND"
"1","(1925,2600)","0","pure_quanta_power","I49";
;
CDS_LIB"pure_quanta_power"
HDL_POWER"GND";
"A"10;
%"74LVC2G07DW7"
"1","(775,1250)","0","pure_quanta","I50";
;
LOCATION"U257"
$SEC"1"
CDS_SEC"1"
PART_TYPE"SMLF"
VALUE"74LVC2G07DW-7"
MATERIAL"IC"
CDS_LIB"pure_quanta"
NEEDS_NO_SIZE"TRUE"
CDS_LMAN_SYM_OUTLINE"-175,100,175,-100"
PART_NUMBER"AL002G07003";
"VCC"
$PN"5"24;
"GND"
$PN"2"16;
"2Y"
$PN"4"22;
"1Y"
$PN"6"20;
"2A"
$PN"3"16;
"1A"
$PN"1"18;
%"Q_RES"
"1","(2325,1800)","0","pure_quanta","I53";
;
LOCATION"R3497"
$SEC"1"
CDS_SEC"1"
VALUE"33.2"
PACK_TYPE"0402LF"
MATERIAL"CHIP"
CDS_LIB"pure_quanta"
TOLERANCE"1%"
WATTAGE"1/16W"
PART_NUMBER"CS03322FB03";
"B"
$PN"2"25;
"A"
$PN"1"20;
%"UNIVERSAL_POWER"
"1","(2075,2350)","0","pure_quanta_power","I54";
;
HDL_POWER"P3V3_AUX"
CDS_LIB"pure_quanta_power";
"A"11;
%"Q_RES"
"2","(2075,2100)","0","pure_quanta","I55";
;
LOCATION"R3494"
$SEC"1"
CDS_SEC"1"
PACK_TYPE"0402LF"
TOLERANCE"1%"
WATTAGE"1/16W"
MATERIAL"CHIP"
VALUE"54.9K"
CDS_LIB"pure_quanta"
PART_NUMBER"CS35492FB03";
"A"
$PN"1"11;
"B"
$PN"2"20;
%"UNIVERSAL_POWER"
"1","(-650,2325)","0","pure_quanta_power","I56";
;
HDL_POWER"P3V3_AUX"
CDS_LIB"pure_quanta_power";
"A"12;
%"Q_RES"
"2","(-650,2075)","0","pure_quanta","I57";
;
LOCATION"R3490"
$SEC"1"
CDS_SEC"1"
PACK_TYPE"0402LF"
WATTAGE"1/16W"
MATERIAL"CHIP"
VALUE"1K"
TOLERANCE"1%"
CDS_LIB"pure_quanta"
PART_NUMBER"CS21002FB06";
"A"
$PN"1"12;
"B"
$PN"2"18;
%"Q_RES"
"2","(2100,1500)","0","pure_quanta","I62";
;
LOCATION"R3495"
$SEC"1"
CDS_SEC"1"
VALUE"100K"
PACK_TYPE"0402LF"
WATTAGE"1/16W"
TOLERANCE"1%"
MATERIAL"EMPTY"
CDS_LIB"pure_quanta"
PART_NUMBER"CS41002FB09";
"A"
$PN"1"20;
"B"
$PN"2"13;
%"UNIVERSAL_GND"
"1","(2100,1300)","0","pure_quanta_power","I63";
;
CDS_LIB"pure_quanta_power"
HDL_POWER"GND";
"A"13;
%"UNIVERSAL_POWER"
"1","(1350,1375)","0","pure_quanta_power","I66";
;
HDL_POWER"P3V3_AUX"
CDS_LIB"pure_quanta_power";
"A"24;
%"Q_CAP"
"1","(1350,1050)","0","pure_quanta","I67";
;
LOCATION"C1979"
$SEC"1"
CDS_SEC"1"
PACK_TYPE"0402"
MATERIAL"X7R"
VOLTAGE"25V"
VALUE"0.1UF"
TOLERANCE"10%"
CDS_LIB"pure_quanta"
PART_NUMBER"CH4104K1B00";
"B"
$PN"2"14;
"A"
$PN"1"24;
%"UNIVERSAL_GND"
"1","(1350,825)","0","pure_quanta_power","I68";
;
CDS_LIB"pure_quanta_power"
HDL_POWER"GND";
"A"14;
%"UNIVERSAL_GND"
"1","(200,1100)","0","pure_quanta_power","I69";
;
CDS_LIB"pure_quanta_power"
HDL_POWER"GND";
"A"16;
%"Q_RES"
"2","(-600,1600)","0","pure_quanta","I70";
;
LOCATION"R3491"
$SEC"1"
CDS_SEC"1"
VALUE"100K"
TOLERANCE"1%"
WATTAGE"1/16W"
PACK_TYPE"0402LF"
MATERIAL"EMPTY"
CDS_LIB"pure_quanta"
PART_NUMBER"CS41002FB09";
"A"
$PN"1"18;
"B"
$PN"2"15;
%"UNIVERSAL_GND"
"1","(-600,1400)","0","pure_quanta_power","I74";
;
CDS_LIB"pure_quanta_power"
HDL_POWER"GND";
"A"15;
%"Q_RES"
"2","(-650,4575)","0","pure_quanta","I75";
;
LOCATION"R3459"
$SEC"1"
CDS_SEC"1"
VALUE"1K"
TOLERANCE"1%"
PACK_TYPE"0402LF"
MATERIAL"CHIP"
WATTAGE"1/16W"
CDS_LIB"pure_quanta"
PART_NUMBER"CS21002FB06";
"A"
$PN"1"3;
"B"
$PN"2"17;
END.
